(kicad_pcb
	(version 20260206)
	(generator "pcbnew")
	(generator_version "10.0")
	(general
		(thickness 1.6)
		(legacy_teardrops no)
	)
	(paper "A4")
	(title_block
		(title "01162023_DA0F0TEBIF0_F0T_Expander_BD_F_brd_V02_OCP.brd")
		(comment 1 "Grand Teton / footprints 2697-2702 of 9728")
	)
	(layers
		(0 "F.Cu" signal "TOP")
		(4 "In1.Cu" signal "GND")
		(6 "In2.Cu" signal "VCC")
		(8 "In3.Cu" signal "VCC1")
		(10 "In4.Cu" signal "GND1")
		(12 "In5.Cu" signal "IN1")
		(14 "In6.Cu" signal "GND2")
		(16 "In7.Cu" signal "IN2")
		(18 "In8.Cu" signal "GND3")
		(20 "In9.Cu" signal "IN3")
		(22 "In10.Cu" signal "GND4")
		(24 "In11.Cu" signal "IN4")
		(26 "In12.Cu" signal "GND5")
		(28 "In13.Cu" signal "IN5")
		(30 "In14.Cu" signal "GND6")
		(32 "In15.Cu" signal "IN6")
		(34 "In16.Cu" signal "GND7")
		(2 "B.Cu" signal "BOTTOM")
		(9 "F.Adhes" user "F.Adhesive")
		(11 "B.Adhes" user "B.Adhesive")
		(13 "F.Paste" user "Package Geometry/Pastemask Top")
		(15 "B.Paste" user "Package Geometry/Pastemask Bottom")
		(5 "F.SilkS" user "Ref Des/Silkscreen Top")
		(7 "B.SilkS" user "Ref Des/Silkscreen Bottom")
		(1 "F.Mask" user "Board Geometry/Soldermask Top")
		(3 "B.Mask" user "Board Geometry/Soldermask Bottom")
		(17 "Dwgs.User" user "User.Drawings")
		(19 "Cmts.User" user "User.Comments")
		(21 "Eco1.User" user "User.Eco1")
		(23 "Eco2.User" user "User.Eco2")
		(25 "Edge.Cuts" user "Board Geometry/Outline")
		(27 "Margin" user)
		(31 "F.CrtYd" user "Package Geometry/Place Bound Top")
		(29 "B.CrtYd" user "Package Geometry/Place Bound Bottom")
		(35 "F.Fab" user "Ref Des/Assembly Top")
		(33 "B.Fab" user "Ref Des/Assembly Bottom")
	)
	(footprint ""
		(layer "F.Cu")
		(at 54.782466 -29.875734)
		(property "Reference" "PU83"
			(at -3.405886 -1.754632 90)
			(unlocked yes)
			(layer "F.SilkS")
			(effects
				(font
					(size 0.7874 0.5842)
					(thickness 0.1524)
				)
			)
		)
		(property "Value" ""
			(at 0 0 0)
			(layer "F.Fab")
			(effects
				(font
					(size 1.27 1.27)
				)
			)
		)
		(duplicate_pad_numbers_are_jumpers no)
		(fp_line
			(start -1.239774 -1.495298)
			(end 1.239774 -1.495298)
			(stroke
				(width 0.1524)
				(type default)
			)
			(layer "F.SilkS")
		)
		(fp_line
			(start -1.239774 1.495298)
			(end -1.239774 -1.495298)
			(stroke
				(width 0.1524)
				(type default)
			)
			(layer "F.SilkS")
		)
		(fp_line
			(start 1.239774 -1.495298)
			(end 1.239774 1.495298)
			(stroke
				(width 0.1524)
				(type default)
			)
			(layer "F.SilkS")
		)
		(fp_line
			(start 1.239774 1.495298)
			(end -1.239774 1.495298)
			(stroke
				(width 0.1524)
				(type default)
			)
			(layer "F.SilkS")
		)
		(fp_poly
			(pts
				(xy -2.24282 -1.504188) (xy -2.961132 -0.785876) (xy -1.88341 -0.42672)
			)
			(stroke
				(width 0)
				(type default)
			)
			(fill yes)
			(layer "F.SilkS")
		)
		(fp_line
			(start -0.8001 -1.050036)
			(end 0.8001 -1.050036)
			(stroke
				(width 0.1)
				(type default)
			)
			(layer "F.Fab")
		)
		(fp_line
			(start -0.8001 1.050036)
			(end -0.8001 -1.050036)
			(stroke
				(width 0.1)
				(type default)
			)
			(layer "F.Fab")
		)
		(fp_line
			(start 0.8001 -1.050036)
			(end 0.8001 1.050036)
			(stroke
				(width 0.1)
				(type default)
			)
			(layer "F.Fab")
		)
		(fp_line
			(start 0.8001 1.050036)
			(end -0.8001 1.050036)
			(stroke
				(width 0.1)
				(type default)
			)
			(layer "F.Fab")
		)
		(fp_poly
			(pts
				(xy -2.458974 -0.508) (xy -2.458974 0.508) (xy -1.442974 0)
			)
			(stroke
				(width 0)
				(type default)
			)
			(fill yes)
			(layer "F.Fab")
		)
		(pad "1_2" smd circle
			(at -0.374904 0 90)
			(size 0 0)
			(layers "F.Cu" "F.Mask" "F.Paste")
			(net "P3V3_AUX")
		)
		(pad "3" smd rect
			(at -0.499872 0.999998)
			(size 0.254 0.7112)
			(layers "F.Cu" "F.Mask" "F.Paste")
			(net "GND")
		)
		(pad "4" smd rect
			(at 0 0.999998)
			(size 0.254 0.7112)
			(layers "F.Cu" "F.Mask" "F.Paste")
			(net "P3V3_SSD2_CO_ILIMIT")
		)
		(pad "5" smd rect
			(at 0.499872 0.999998)
			(size 0.254 0.7112)
			(layers "F.Cu" "F.Mask" "F.Paste")
			(net "P3V3_SSD2_CO_MODE")
		)
		(pad "6_7" smd circle
			(at 0.374904 0 270)
			(size 0 0)
			(layers "F.Cu" "F.Mask" "F.Paste")
			(net "P3V3_SSD2")
		)
		(pad "8" smd rect
			(at 0.499872 -0.999998)
			(size 0.254 0.7112)
			(layers "F.Cu" "F.Mask" "F.Paste")
			(net "P3V3_SSD2_CO_GATE")
		)
		(pad "9" smd rect
			(at 0 -0.999998)
			(size 0.254 0.7112)
			(layers "F.Cu" "F.Mask" "F.Paste")
			(net "P3V3_SSD2_CO_EN")
		)
		(pad "10" smd rect
			(at -0.499872 -0.999998)
			(size 0.254 0.7112)
			(layers "F.Cu" "F.Mask" "F.Paste")
			(net "P3V3_SSD2_CO_DV_DT")
		)
	)
	(footprint ""
		(layer "F.Cu")
		(at 321.223386 -96.811592 -90)
		(property "Reference" "R737"
			(at 0 0 270)
			(layer "F.SilkS")
			(hide yes)
			(effects
				(font
					(size 1.27 1.27)
				)
			)
		)
		(property "Value" ""
			(at 0 0 270)
			(layer "F.Fab")
			(effects
				(font
					(size 1.27 1.27)
				)
			)
		)
		(duplicate_pad_numbers_are_jumpers no)
		(fp_line
			(start -0.7874 0.4064)
			(end -0.7874 -0.4064)
			(stroke
				(width 0.1524)
				(type default)
			)
			(layer "F.SilkS")
		)
		(fp_line
			(start 0.7874 0.4064)
			(end -0.7874 0.4064)
			(stroke
				(width 0.1524)
				(type default)
			)
			(layer "F.SilkS")
		)
		(fp_line
			(start -0.7874 -0.4064)
			(end 0.7874 -0.4064)
			(stroke
				(width 0.1524)
				(type default)
			)
			(layer "F.SilkS")
		)
		(fp_line
			(start 0.7874 -0.4064)
			(end 0.7874 0.4064)
			(stroke
				(width 0.1524)
				(type default)
			)
			(layer "F.SilkS")
		)
		(fp_line
			(start -0.67945 0.3048)
			(end -0.67945 -0.305054)
			(stroke
				(width 0.1)
				(type default)
			)
			(layer "F.Fab")
		)
		(fp_line
			(start -0.12065 0.3048)
			(end -0.67945 0.3048)
			(stroke
				(width 0.1)
				(type default)
			)
			(layer "F.Fab")
		)
		(fp_line
			(start 0.120396 0.3048)
			(end 0.120396 0.2794)
			(stroke
				(width 0.1)
				(type default)
			)
			(layer "F.Fab")
		)
		(fp_line
			(start 0.67945 0.3048)
			(end 0.120396 0.3048)
			(stroke
				(width 0.1)
				(type default)
			)
			(layer "F.Fab")
		)
		(fp_line
			(start -0.12065 0.2794)
			(end -0.12065 0.3048)
			(stroke
				(width 0.1)
				(type default)
			)
			(layer "F.Fab")
		)
		(fp_line
			(start 0.120396 0.2794)
			(end -0.12065 0.2794)
			(stroke
				(width 0.1)
				(type default)
			)
			(layer "F.Fab")
		)
		(fp_line
			(start -0.12065 -0.2794)
			(end 0.12065 -0.2794)
			(stroke
				(width 0.1)
				(type default)
			)
			(layer "F.Fab")
		)
		(fp_line
			(start 0.12065 -0.2794)
			(end 0.12065 -0.3048)
			(stroke
				(width 0.1)
				(type default)
			)
			(layer "F.Fab")
		)
		(fp_line
			(start 0.12065 -0.3048)
			(end 0.67945 -0.3048)
			(stroke
				(width 0.1)
				(type default)
			)
			(layer "F.Fab")
		)
		(fp_line
			(start 0.67945 -0.3048)
			(end 0.67945 0.3048)
			(stroke
				(width 0.1)
				(type default)
			)
			(layer "F.Fab")
		)
		(fp_line
			(start -0.67945 -0.305054)
			(end -0.12065 -0.305054)
			(stroke
				(width 0.1)
				(type default)
			)
			(layer "F.Fab")
		)
		(fp_line
			(start -0.12065 -0.305054)
			(end -0.12065 -0.2794)
			(stroke
				(width 0.1)
				(type default)
			)
			(layer "F.Fab")
		)
		(pad "1" smd circle
			(at -0.40005 0 270)
			(size 0 0)
			(layers "F.Cu" "F.Mask" "F.Paste")
			(net "NIC5_ADC_A0")
		)
		(pad "2" smd circle
			(at 0.40005 0 270)
			(size 0 0)
			(layers "F.Cu" "F.Mask" "F.Paste")
			(net "P3V3_AUX")
		)
	)
	(footprint ""
		(layer "F.Cu")
		(at 344.612976 -89.255346 180)
		(property "Reference" "R1182"
			(at 0 0 180)
			(layer "F.SilkS")
			(hide yes)
			(effects
				(font
					(size 1.27 1.27)
				)
			)
		)
		(property "Value" ""
			(at 0 0 180)
			(layer "F.Fab")
			(effects
				(font
					(size 1.27 1.27)
				)
			)
		)
		(duplicate_pad_numbers_are_jumpers no)
		(fp_line
			(start -0.7874 -0.4064)
			(end 0.7874 -0.4064)
			(stroke
				(width 0.1524)
				(type default)
			)
			(layer "F.SilkS")
		)
		(fp_line
			(start 0.67945 0.3048)
			(end 0.120396 0.3048)
			(stroke
				(width 0.1)
				(type default)
			)
			(layer "F.Fab")
		)
		(fp_line
			(start 0.67945 -0.3048)
			(end 0.67945 0.3048)
			(stroke
				(width 0.1)
				(type default)
			)
			(layer "F.Fab")
		)
		(fp_line
			(start 0.12065 -0.2794)
			(end 0.12065 -0.3048)
			(stroke
				(width 0.1)
				(type default)
			)
			(layer "F.Fab")
		)
		(fp_line
			(start 0.12065 -0.3048)
			(end 0.67945 -0.3048)
			(stroke
				(width 0.1)
				(type default)
			)
			(layer "F.Fab")
		)
		(fp_line
			(start 0.120396 0.3048)
			(end 0.120396 0.2794)
			(stroke
				(width 0.1)
				(type default)
			)
			(layer "F.Fab")
		)
		(fp_line
			(start 0.120396 0.2794)
			(end -0.12065 0.2794)
			(stroke
				(width 0.1)
				(type default)
			)
			(layer "F.Fab")
		)
		(fp_line
			(start -0.12065 0.3048)
			(end -0.67945 0.3048)
			(stroke
				(width 0.1)
				(type default)
			)
			(layer "F.Fab")
		)
		(fp_line
			(start -0.12065 0.2794)
			(end -0.12065 0.3048)
			(stroke
				(width 0.1)
				(type default)
			)
			(layer "F.Fab")
		)
		(fp_line
			(start -0.12065 -0.2794)
			(end 0.12065 -0.2794)
			(stroke
				(width 0.1)
				(type default)
			)
			(layer "F.Fab")
		)
		(fp_line
			(start -0.12065 -0.305054)
			(end -0.12065 -0.2794)
			(stroke
				(width 0.1)
				(type default)
			)
			(layer "F.Fab")
		)
		(fp_line
			(start -0.67945 0.3048)
			(end -0.67945 -0.305054)
			(stroke
				(width 0.1)
				(type default)
			)
			(layer "F.Fab")
		)
		(fp_line
			(start -0.67945 -0.305054)
			(end -0.12065 -0.305054)
			(stroke
				(width 0.1)
				(type default)
			)
			(layer "F.Fab")
		)
		(pad "1" smd circle
			(at -0.40005 0 180)
			(size 0 0)
			(layers "F.Cu" "F.Mask" "F.Paste")
			(net "CLK_100M_DB800ZL_SSD14_R_DP")
		)
		(pad "2" smd circle
			(at 0.40005 0 180)
			(size 0 0)
			(layers "F.Cu" "F.Mask" "F.Paste")
			(net "CLK_100M_DB800ZL_SSD14_DP")
		)
	)
	(footprint ""
		(layer "F.Cu")
		(at 291.194998 -100.766372 180)
		(property "Reference" "R282"
			(at 0 0 180)
			(layer "F.SilkS")
			(hide yes)
			(effects
				(font
					(size 1.27 1.27)
				)
			)
		)
		(property "Value" ""
			(at 0 0 180)
			(layer "F.Fab")
			(effects
				(font
					(size 1.27 1.27)
				)
			)
		)
		(duplicate_pad_numbers_are_jumpers no)
		(fp_line
			(start 0.7874 0.4064)
			(end -0.7874 0.4064)
			(stroke
				(width 0.1524)
				(type default)
			)
			(layer "F.SilkS")
		)
		(fp_line
			(start 0.7874 -0.4064)
			(end 0.7874 0.4064)
			(stroke
				(width 0.1524)
				(type default)
			)
			(layer "F.SilkS")
		)
		(fp_line
			(start -0.7874 0.4064)
			(end -0.7874 -0.4064)
			(stroke
				(width 0.1524)
				(type default)
			)
			(layer "F.SilkS")
		)
		(fp_line
			(start -0.7874 -0.4064)
			(end 0.7874 -0.4064)
			(stroke
				(width 0.1524)
				(type default)
			)
			(layer "F.SilkS")
		)
		(fp_line
			(start 0.67945 0.3048)
			(end 0.120396 0.3048)
			(stroke
				(width 0.1)
				(type default)
			)
			(layer "F.Fab")
		)
		(fp_line
			(start 0.67945 -0.3048)
			(end 0.67945 0.3048)
			(stroke
				(width 0.1)
				(type default)
			)
			(layer "F.Fab")
		)
		(fp_line
			(start 0.12065 -0.2794)
			(end 0.12065 -0.3048)
			(stroke
				(width 0.1)
				(type default)
			)
			(layer "F.Fab")
		)
		(fp_line
			(start 0.12065 -0.3048)
			(end 0.67945 -0.3048)
			(stroke
				(width 0.1)
				(type default)
			)
			(layer "F.Fab")
		)
		(fp_line
			(start 0.120396 0.3048)
			(end 0.120396 0.2794)
			(stroke
				(width 0.1)
				(type default)
			)
			(layer "F.Fab")
		)
		(fp_line
			(start 0.120396 0.2794)
			(end -0.12065 0.2794)
			(stroke
				(width 0.1)
				(type default)
			)
			(layer "F.Fab")
		)
		(fp_line
			(start -0.12065 0.3048)
			(end -0.67945 0.3048)
			(stroke
				(width 0.1)
				(type default)
			)
			(layer "F.Fab")
		)
		(fp_line
			(start -0.12065 0.2794)
			(end -0.12065 0.3048)
			(stroke
				(width 0.1)
				(type default)
			)
			(layer "F.Fab")
		)
		(fp_line
			(start -0.12065 -0.2794)
			(end 0.12065 -0.2794)
			(stroke
				(width 0.1)
				(type default)
			)
			(layer "F.Fab")
		)
		(fp_line
			(start -0.12065 -0.305054)
			(end -0.12065 -0.2794)
			(stroke
				(width 0.1)
				(type default)
			)
			(layer "F.Fab")
		)
		(fp_line
			(start -0.67945 0.3048)
			(end -0.67945 -0.305054)
			(stroke
				(width 0.1)
				(type default)
			)
			(layer "F.Fab")
		)
		(fp_line
			(start -0.67945 -0.305054)
			(end -0.12065 -0.305054)
			(stroke
				(width 0.1)
				(type default)
			)
			(layer "F.Fab")
		)
		(pad "1" smd circle
			(at -0.40005 0 180)
			(size 0 0)
			(layers "F.Cu" "F.Mask" "F.Paste")
			(net "NIC5_SLOT_ID1")
		)
		(pad "2" smd circle
			(at 0.40005 0 180)
			(size 0 0)
			(layers "F.Cu" "F.Mask" "F.Paste")
			(net "P3V3_NIC5")
		)
	)
	(footprint ""
		(layer "F.Cu")
		(at 254.085598 -27.092148 -90)
		(property "Reference" "R5759"
			(at 0 0 270)
			(layer "F.SilkS")
			(hide yes)
			(effects
				(font
					(size 1.27 1.27)
				)
			)
		)
		(property "Value" ""
			(at 0 0 270)
			(layer "F.Fab")
			(effects
				(font
					(size 1.27 1.27)
				)
			)
		)
		(duplicate_pad_numbers_are_jumpers no)
		(fp_line
			(start -0.7874 0.4064)
			(end -0.7874 -0.4064)
			(stroke
				(width 0.1524)
				(type default)
			)
			(layer "F.SilkS")
		)
		(fp_line
			(start 0.7874 0.4064)
			(end -0.7874 0.4064)
			(stroke
				(width 0.1524)
				(type default)
			)
			(layer "F.SilkS")
		)
		(fp_line
			(start -0.7874 -0.4064)
			(end 0.7874 -0.4064)
			(stroke
				(width 0.1524)
				(type default)
			)
			(layer "F.SilkS")
		)
		(fp_line
			(start 0.7874 -0.4064)
			(end 0.7874 0.4064)
			(stroke
				(width 0.1524)
				(type default)
			)
			(layer "F.SilkS")
		)
		(fp_line
			(start -0.67945 0.3048)
			(end -0.67945 -0.305054)
			(stroke
				(width 0.1)
				(type default)
			)
			(layer "F.Fab")
		)
		(fp_line
			(start -0.12065 0.3048)
			(end -0.67945 0.3048)
			(stroke
				(width 0.1)
				(type default)
			)
			(layer "F.Fab")
		)
		(fp_line
			(start 0.120396 0.3048)
			(end 0.120396 0.2794)
			(stroke
				(width 0.1)
				(type default)
			)
			(layer "F.Fab")
		)
		(fp_line
			(start 0.67945 0.3048)
			(end 0.120396 0.3048)
			(stroke
				(width 0.1)
				(type default)
			)
			(layer "F.Fab")
		)
		(fp_line
			(start -0.12065 0.2794)
			(end -0.12065 0.3048)
			(stroke
				(width 0.1)
				(type default)
			)
			(layer "F.Fab")
		)
		(fp_line
			(start 0.120396 0.2794)
			(end -0.12065 0.2794)
			(stroke
				(width 0.1)
				(type default)
			)
			(layer "F.Fab")
		)
		(fp_line
			(start -0.12065 -0.2794)
			(end 0.12065 -0.2794)
			(stroke
				(width 0.1)
				(type default)
			)
			(layer "F.Fab")
		)
		(fp_line
			(start 0.12065 -0.2794)
			(end 0.12065 -0.3048)
			(stroke
				(width 0.1)
				(type default)
			)
			(layer "F.Fab")
		)
		(fp_line
			(start 0.12065 -0.3048)
			(end 0.67945 -0.3048)
			(stroke
				(width 0.1)
				(type default)
			)
			(layer "F.Fab")
		)
		(fp_line
			(start 0.67945 -0.3048)
			(end 0.67945 0.3048)
			(stroke
				(width 0.1)
				(type default)
			)
			(layer "F.Fab")
		)
		(fp_line
			(start -0.67945 -0.305054)
			(end -0.12065 -0.305054)
			(stroke
				(width 0.1)
				(type default)
			)
			(layer "F.Fab")
		)
		(fp_line
			(start -0.12065 -0.305054)
			(end -0.12065 -0.2794)
			(stroke
				(width 0.1)
				(type default)
			)
			(layer "F.Fab")
		)
		(pad "1" smd circle
			(at -0.40005 0 270)
			(size 0 0)
			(layers "F.Cu" "F.Mask" "F.Paste")
			(net "P3V3_SSD8")
		)
		(pad "2" smd circle
			(at 0.40005 0 270)
			(size 0 0)
			(layers "F.Cu" "F.Mask" "F.Paste")
			(net "SSD8_LED_ISO_N")
		)
	)
	(footprint ""
		(layer "F.Cu")
		(at 59.373262 -390.07161 -90)
		(property "Reference" "R1826"
			(at 0 0 270)
			(layer "F.SilkS")
			(hide yes)
			(effects
				(font
					(size 1.27 1.27)
				)
			)
		)
		(property "Value" ""
			(at 0 0 270)
			(layer "F.Fab")
			(effects
				(font
					(size 1.27 1.27)
				)
			)
		)
		(duplicate_pad_numbers_are_jumpers no)
		(fp_line
			(start -0.7874 0.4064)
			(end -0.7874 -0.4064)
			(stroke
				(width 0.1524)
				(type default)
			)
			(layer "F.SilkS")
		)
		(fp_line
			(start 0.7874 0.4064)
			(end -0.7874 0.4064)
			(stroke
				(width 0.1524)
				(type default)
			)
			(layer "F.SilkS")
		)
		(fp_line
			(start -0.7874 -0.4064)
			(end 0.7874 -0.4064)
			(stroke
				(width 0.1524)
				(type default)
			)
			(layer "F.SilkS")
		)
		(fp_line
			(start 0.7874 -0.4064)
			(end 0.7874 0.4064)
			(stroke
				(width 0.1524)
				(type default)
			)
			(layer "F.SilkS")
		)
		(fp_line
			(start -0.67945 0.3048)
			(end -0.67945 -0.305054)
			(stroke
				(width 0.1)
				(type default)
			)
			(layer "F.Fab")
		)
		(fp_line
			(start -0.12065 0.3048)
			(end -0.67945 0.3048)
			(stroke
				(width 0.1)
				(type default)
			)
			(layer "F.Fab")
		)
		(fp_line
			(start 0.120396 0.3048)
			(end 0.120396 0.2794)
			(stroke
				(width 0.1)
				(type default)
			)
			(layer "F.Fab")
		)
		(fp_line
			(start 0.67945 0.3048)
			(end 0.120396 0.3048)
			(stroke
				(width 0.1)
				(type default)
			)
			(layer "F.Fab")
		)
		(fp_line
			(start -0.12065 0.2794)
			(end -0.12065 0.3048)
			(stroke
				(width 0.1)
				(type default)
			)
			(layer "F.Fab")
		)
		(fp_line
			(start 0.120396 0.2794)
			(end -0.12065 0.2794)
			(stroke
				(width 0.1)
				(type default)
			)
			(layer "F.Fab")
		)
		(fp_line
			(start -0.12065 -0.2794)
			(end 0.12065 -0.2794)
			(stroke
				(width 0.1)
				(type default)
			)
			(layer "F.Fab")
		)
		(fp_line
			(start 0.12065 -0.2794)
			(end 0.12065 -0.3048)
			(stroke
				(width 0.1)
				(type default)
			)
			(layer "F.Fab")
		)
		(fp_line
			(start 0.12065 -0.3048)
			(end 0.67945 -0.3048)
			(stroke
				(width 0.1)
				(type default)
			)
			(layer "F.Fab")
		)
		(fp_line
			(start 0.67945 -0.3048)
			(end 0.67945 0.3048)
			(stroke
				(width 0.1)
				(type default)
			)
			(layer "F.Fab")
		)
		(fp_line
			(start -0.67945 -0.305054)
			(end -0.12065 -0.305054)
			(stroke
				(width 0.1)
				(type default)
			)
			(layer "F.Fab")
		)
		(fp_line
			(start -0.12065 -0.305054)
			(end -0.12065 -0.2794)
			(stroke
				(width 0.1)
				(type default)
			)
			(layer "F.Fab")
		)
		(pad "1" smd circle
			(at -0.40005 0 270)
			(size 0 0)
			(layers "F.Cu" "F.Mask" "F.Paste")
			(net "RST_GPU_FPGA_PEX_RST_R_N")
		)
		(pad "2" smd circle
			(at 0.40005 0 270)
			(size 0 0)
			(layers "F.Cu" "F.Mask" "F.Paste")
			(net "RST_GPU_FPGA_PEX_RST_N")
		)
	)
)
